(kicad_pcb
	(version 20241229)
	(generator "pcbnew")
	(generator_version "9.0")
	(general
		(thickness 1.62)
		(legacy_teardrops no)
	)
	(paper "A4")
	(title_block
		(title "OCuLink to 10GbE adapter")
		(date "2026-02-23")
		(rev "1.1.0")
		(company "Antmicro Ltd")
		(comment 1 "www.antmicro.com")
		(comment 9 "footprints 1-5 of 510")
	)
	(layers
		(0 "F.Cu" signal)
		(4 "In1.Cu" signal)
		(6 "In2.Cu" signal)
		(8 "In3.Cu" signal)
		(10 "In4.Cu" signal)
		(12 "In5.Cu" signal)
		(14 "In6.Cu" signal)
		(2 "B.Cu" signal)
		(9 "F.Adhes" user "F.Adhesive")
		(11 "B.Adhes" user "B.Adhesive")
		(13 "F.Paste" user)
		(15 "B.Paste" user)
		(5 "F.SilkS" user "F.Silkscreen")
		(7 "B.SilkS" user "B.Silkscreen")
		(1 "F.Mask" user)
		(3 "B.Mask" user)
		(17 "Dwgs.User" user "User.Drawings")
		(19 "Cmts.User" user "User.Comments")
		(21 "Eco1.User" user "User.Eco1")
		(23 "Eco2.User" user "User.Eco2")
		(25 "Edge.Cuts" user)
		(27 "Margin" user)
		(31 "F.CrtYd" user "F.Courtyard")
		(29 "B.CrtYd" user "B.Courtyard")
		(35 "F.Fab" user)
		(33 "B.Fab" user)
	)
	(footprint "antmicro-footprints:R_0402_1005Metric"
		(layer "F.Cu")
		(at 97.4 105.2)
		(descr "Resistor SMD 0402")
		(tags "resistor SMD 0402")
		(property "Reference" "R7"
			(at -2.25 15.3 0)
			(layer "F.SilkS")
			(effects
				(font
					(size 0.7 0.7)
					(thickness 0.15)
				)
				(justify left bottom)
			)
		)
		(property "Value" "R_10k_0402"
			(at -1.011843 1.772046 0)
			(layer "F.Fab")
			(hide yes)
			(effects
				(font
					(size 0.7 0.7)
					(thickness 0.15)
				)
				(justify left bottom)
			)
		)
		(property "Datasheet" "https://www.bourns.com/docs/product-datasheets/cr.pdf"
			(at 0 0 0)
			(layer "F.Fab")
			(hide yes)
			(effects
				(font
					(size 1.27 1.27)
					(thickness 0.15)
				)
			)
		)
		(property "Description" "SMD Chip Resistor, 10 kohm, ± 1%, 62.5 mW, 0402 [1005 Metric], Thick Film, General Purpose"
			(at 0 0 0)
			(layer "F.Fab")
			(hide yes)
			(effects
				(font
					(size 1.27 1.27)
					(thickness 0.15)
				)
			)
		)
		(property "MPN" "CR0402-FX-1002GLF"
			(at 0 0 0)
			(unlocked yes)
			(layer "F.Fab")
			(hide yes)
			(effects
				(font
					(size 1 1)
					(thickness 0.15)
				)
			)
		)
		(property "Manufacturer" "Bourns"
			(at 0 0 0)
			(unlocked yes)
			(layer "F.Fab")
			(hide yes)
			(effects
				(font
					(size 1 1)
					(thickness 0.15)
				)
			)
		)
		(property "License" "Apache-2.0"
			(at 0 0 0)
			(unlocked yes)
			(layer "F.Fab")
			(hide yes)
			(effects
				(font
					(size 1 1)
					(thickness 0.15)
				)
			)
		)
		(property "Author" "Antmicro"
			(at 0 0 0)
			(unlocked yes)
			(layer "F.Fab")
			(hide yes)
			(effects
				(font
					(size 1 1)
					(thickness 0.15)
				)
			)
		)
		(property "Val" "10k"
			(at 0 0 0)
			(unlocked yes)
			(layer "F.Fab")
			(hide yes)
			(effects
				(font
					(size 1 1)
					(thickness 0.15)
				)
			)
		)
		(property "Tolerance" "1%"
			(at 0 0 0)
			(unlocked yes)
			(layer "F.Fab")
			(hide yes)
			(effects
				(font
					(size 1 1)
					(thickness 0.15)
				)
			)
		)
		(sheetname "/X710-AT2 Misc/")
		(sheetfile "x710-at2-mics.kicad_sch")
		(attr smd)
		(fp_rect
			(start -0.925 -0.47)
			(end 0.925 0.47)
			(stroke
				(width 0.05)
				(type default)
			)
			(fill no)
			(layer "F.CrtYd")
		)
		(fp_rect
			(start -0.5 -0.25)
			(end 0.5 0.25)
			(stroke
				(width 0.15)
				(type solid)
			)
			(fill no)
			(layer "F.Fab")
		)
		(pad "1" smd roundrect
			(at -0.48 0)
			(size 0.59 0.64)
			(layers "F.Cu" "F.Mask" "F.Paste")
			(roundrect_rratio 0.25)
			(net 133 "/X710-AT2 Misc/MAIN_PWR_OK")
			(pintype "passive")
		)
		(pad "2" smd roundrect
			(at 0.48 0)
			(size 0.59 0.64)
			(layers "F.Cu" "F.Mask" "F.Paste")
			(roundrect_rratio 0.25)
			(net 7 "+3V3")
			(pintype "passive")
		)
	)
	(footprint "antmicro-footprints:USON-10_2.5x1mm_P0.5mm"
		(layer "F.Cu")
		(at 103.248 59.985 -90)
		(descr "USON-10 2.5x1mm_ Pitch 0.5mm")
		(tags "USON-10 2.5x1mm Pitch 0.5mm")
		(property "Reference" "D5"
			(at 1.7 0.698 0)
			(layer "F.SilkS")
			(effects
				(font
					(size 0.7 0.7)
					(thickness 0.15)
				)
				(justify left bottom)
			)
		)
		(property "Value" "ESD204DQAR"
			(at 0.018 2.499 90)
			(layer "F.Fab")
			(hide yes)
			(effects
				(font
					(size 0.7 0.7)
					(thickness 0.15)
				)
				(justify right top)
			)
		)
		(property "Datasheet" "https://www.ti.com/lit/ds/symlink/esd204.pdf?ts=1706004844383&ref_url=https%253A%252F%252Fwww.ti.com%252Finterface%252Fdiodes%252Fesd-protection-diodes%252Fproducts.html"
			(at 0 0 90)
			(layer "F.Fab")
			(hide yes)
			(effects
				(font
					(size 1.27 1.27)
					(thickness 0.15)
				)
			)
		)
		(property "Description" "TVS diode array, 30 kV, USON-10, 3.6 V, 0.55 pF"
			(at 0 0 90)
			(layer "F.Fab")
			(hide yes)
			(effects
				(font
					(size 1.27 1.27)
					(thickness 0.15)
				)
			)
		)
		(property "MPN" "ESD204DQAR"
			(at 0 0 270)
			(unlocked yes)
			(layer "F.Fab")
			(hide yes)
			(effects
				(font
					(size 1 1)
					(thickness 0.15)
				)
			)
		)
		(property "Manufacturer" "Texas Instruments"
			(at 0 0 270)
			(unlocked yes)
			(layer "F.Fab")
			(hide yes)
			(effects
				(font
					(size 1 1)
					(thickness 0.15)
				)
			)
		)
		(property "Author" "Antmicro"
			(at 0 0 270)
			(unlocked yes)
			(layer "F.Fab")
			(hide yes)
			(effects
				(font
					(size 1 1)
					(thickness 0.15)
				)
			)
		)
		(property "License" "Apache-2.0"
			(at 0 0 270)
			(unlocked yes)
			(layer "F.Fab")
			(hide yes)
			(effects
				(font
					(size 1 1)
					(thickness 0.15)
				)
			)
		)
		(sheetname "/OCuLink/")
		(sheetfile "oculink.kicad_sch")
		(attr smd)
		(fp_line
			(start 0.498 1.398)
			(end -0.5 1.398)
			(stroke
				(width 0.15)
				(type solid)
			)
			(layer "F.SilkS")
		)
		(fp_line
			(start 0.498 -1.401)
			(end -0.5 -1.401)
			(stroke
				(width 0.15)
				(type solid)
			)
			(layer "F.SilkS")
		)
		(fp_circle
			(center -0.68 -1.27)
			(end -0.63 -1.27)
			(stroke
				(width 0.15)
				(type solid)
			)
			(fill yes)
			(layer "F.SilkS")
		)
		(fp_rect
			(start -0.8 -1.5)
			(end 0.8 1.499)
			(stroke
				(width 0.05)
				(type solid)
			)
			(fill no)
			(layer "F.CrtYd")
		)
		(fp_line
			(start -0.5 1.249)
			(end 0.498 1.249)
			(stroke
				(width 0.15)
				(type solid)
			)
			(layer "F.Fab")
		)
		(fp_line
			(start -0.5 -1)
			(end -0.5 1.249)
			(stroke
				(width 0.15)
				(type solid)
			)
			(layer "F.Fab")
		)
		(fp_line
			(start -0.25 -1.25)
			(end -0.5 -1)
			(stroke
				(width 0.15)
				(type solid)
			)
			(layer "F.Fab")
		)
		(fp_line
			(start 0.498 -1.25)
			(end 0.498 1.249)
			(stroke
				(width 0.15)
				(type solid)
			)
			(layer "F.Fab")
		)
		(fp_line
			(start 0.498 -1.25)
			(end -0.25 -1.25)
			(stroke
				(width 0.15)
				(type solid)
			)
			(layer "F.Fab")
		)
		(pad "1" smd roundrect
			(at -0.387 -1 180)
			(size 0.25 0.55)
			(layers "F.Cu" "F.Mask" "F.Paste")
			(roundrect_rratio 0.25)
			(net 13 "/OCuLink/PCIe_{x4}.TX0+")
			(pintype "passive")
		)
		(pad "2" smd roundrect
			(at -0.387 -0.5 180)
			(size 0.25 0.55)
			(layers "F.Cu" "F.Mask" "F.Paste")
			(roundrect_rratio 0.25)
			(net 17 "/OCuLink/PCIe_{x4}.TX0-")
			(pintype "passive")
		)
		(pad "3" smd roundrect
			(at -0.387 0 180)
			(size 0.4 0.55)
			(layers "F.Cu" "F.Mask" "F.Paste")
			(roundrect_rratio 0.25)
			(net 28 "GND")
			(pintype "power_in")
		)
		(pad "4" smd roundrect
			(at -0.387 0.498 180)
			(size 0.25 0.55)
			(layers "F.Cu" "F.Mask" "F.Paste")
			(roundrect_rratio 0.25)
			(net 19 "/OCuLink/PCIe_{x4}.TX1+")
			(pintype "passive")
		)
		(pad "5" smd roundrect
			(at -0.387 0.998 180)
			(size 0.25 0.55)
			(layers "F.Cu" "F.Mask" "F.Paste")
			(roundrect_rratio 0.25)
			(net 20 "/OCuLink/PCIe_{x4}.TX1-")
			(pintype "passive")
		)
		(pad "6" smd roundrect
			(at 0.385 0.998 180)
			(size 0.25 0.55)
			(layers "F.Cu" "F.Mask" "F.Paste")
			(roundrect_rratio 0.25)
			(net 20 "/OCuLink/PCIe_{x4}.TX1-")
			(pintype "passive")
		)
		(pad "7" smd roundrect
			(at 0.385 0.498 180)
			(size 0.25 0.55)
			(layers "F.Cu" "F.Mask" "F.Paste")
			(roundrect_rratio 0.25)
			(net 19 "/OCuLink/PCIe_{x4}.TX1+")
			(pintype "passive")
		)
		(pad "8" smd roundrect
			(at 0.385 0 180)
			(size 0.4 0.55)
			(layers "F.Cu" "F.Mask" "F.Paste")
			(roundrect_rratio 0.25)
			(net 28 "GND")
			(pintype "passive")
		)
		(pad "9" smd roundrect
			(at 0.385 -0.5 180)
			(size 0.25 0.55)
			(layers "F.Cu" "F.Mask" "F.Paste")
			(roundrect_rratio 0.25)
			(net 17 "/OCuLink/PCIe_{x4}.TX0-")
			(pintype "passive")
		)
		(pad "10" smd roundrect
			(at 0.385 -1 180)
			(size 0.25 0.55)
			(layers "F.Cu" "F.Mask" "F.Paste")
			(roundrect_rratio 0.25)
			(net 13 "/OCuLink/PCIe_{x4}.TX0+")
			(pintype "passive")
		)
	)
	(footprint "antmicro-footprints:C_0603_1608Metric_EIA"
		(layer "F.Cu")
		(at 70.499998 77.189995 180)
		(descr "Capacitor SMD 0603, IPC-7351 Density Level A")
		(tags "Capacitor 0603")
		(property "Reference" "C4"
			(at 1.149998 0.289995 0)
			(layer "F.SilkS")
			(effects
				(font
					(size 0.7 0.7)
					(thickness 0.15)
				)
				(justify right top)
			)
		)
		(property "Value" "C_22u_16V_0603"
			(at -1.42757 1.770288 0)
			(layer "F.Fab")
			(hide yes)
			(effects
				(font
					(size 0.7 0.7)
					(thickness 0.15)
				)
				(justify right top)
			)
		)
		(property "Datasheet" "https://product.samsungsem.com/mlcc/CL10A226MO7JZN.do"
			(at 0 0 0)
			(layer "F.Fab")
			(hide yes)
			(effects
				(font
					(size 1.27 1.27)
					(thickness 0.15)
				)
			)
		)
		(property "Description" "SMD Multilayer Ceramic Capacitor"
			(at 0 0 0)
			(layer "F.Fab")
			(hide yes)
			(effects
				(font
					(size 1.27 1.27)
					(thickness 0.15)
				)
			)
		)
		(property "MPN" "CL10A226MO7JZNC"
			(at 0 0 180)
			(unlocked yes)
			(layer "F.Fab")
			(hide yes)
			(effects
				(font
					(size 1 1)
					(thickness 0.15)
				)
			)
		)
		(property "Manufacturer" "Samsung Electro-Mechanics"
			(at 0 0 180)
			(unlocked yes)
			(layer "F.Fab")
			(hide yes)
			(effects
				(font
					(size 1 1)
					(thickness 0.15)
				)
			)
		)
		(property "License" "Apache-2.0"
			(at 0 0 180)
			(unlocked yes)
			(layer "F.Fab")
			(hide yes)
			(effects
				(font
					(size 1 1)
					(thickness 0.15)
				)
			)
		)
		(property "Author" "Antmicro"
			(at 0 0 180)
			(unlocked yes)
			(layer "F.Fab")
			(hide yes)
			(effects
				(font
					(size 1 1)
					(thickness 0.15)
				)
			)
		)
		(property "Val" "22u"
			(at 0 0 180)
			(unlocked yes)
			(layer "F.Fab")
			(hide yes)
			(effects
				(font
					(size 1 1)
					(thickness 0.15)
				)
			)
		)
		(property "Voltage" "16V"
			(at 0 0 180)
			(unlocked yes)
			(layer "F.Fab")
			(hide yes)
			(effects
				(font
					(size 1 1)
					(thickness 0.15)
				)
			)
		)
		(property "Dielectric" ""
			(at 0 0 180)
			(unlocked yes)
			(layer "F.Fab")
			(hide yes)
			(effects
				(font
					(size 1 1)
					(thickness 0.15)
				)
			)
		)
		(property "Public" "False"
			(at 0 0 180)
			(unlocked yes)
			(layer "F.Fab")
			(hide yes)
			(effects
				(font
					(size 1 1)
					(thickness 0.15)
				)
			)
		)
		(sheetname "/Power/")
		(sheetfile "power.kicad_sch")
		(attr smd)
		(fp_line
			(start -0.15 0.55)
			(end 0.15 0.55)
			(stroke
				(width 0.15)
				(type solid)
			)
			(layer "F.SilkS")
		)
		(fp_line
			(start -0.15 -0.55)
			(end 0.15 -0.55)
			(stroke
				(width 0.15)
				(type solid)
			)
			(layer "F.SilkS")
		)
		(fp_rect
			(start -1.25 -0.65)
			(end 1.25 0.65)
			(stroke
				(width 0.05)
				(type solid)
			)
			(fill no)
			(layer "F.CrtYd")
		)
		(fp_rect
			(start -0.8 -0.45)
			(end 0.8 0.45)
			(stroke
				(width 0.15)
				(type solid)
			)
			(fill no)
			(layer "F.Fab")
		)
		(pad "1" smd roundrect
			(at -0.7 0 180)
			(size 0.8 1.1)
			(layers "F.Cu" "F.Mask" "F.Paste")
			(roundrect_rratio 0.2)
			(net 28 "GND")
			(pintype "passive")
		)
		(pad "2" smd roundrect
			(at 0.7 0 180)
			(size 0.8 1.1)
			(layers "F.Cu" "F.Mask" "F.Paste")
			(roundrect_rratio 0.2)
			(net 314 "VCC")
			(pintype "passive")
		)
	)
	(footprint "antmicro-footprints:C_0402_1005Metric"
		(layer "F.Cu")
		(at 70.9445 105.91 -90)
		(descr "Capacitor SMD 0402")
		(tags "capacitor SMD 0402")
		(property "Reference" "C73"
			(at 0.69 0.3245 90)
			(layer "F.SilkS")
			(effects
				(font
					(size 0.7 0.7)
					(thickness 0.15)
				)
				(justify right top)
			)
		)
		(property "Value" "C_5p6_0402"
			(at -1.022927 2.155213 90)
			(layer "F.Fab")
			(hide yes)
			(effects
				(font
					(size 0.7 0.7)
					(thickness 0.15)
				)
				(justify right top)
			)
		)
		(property "Datasheet" "https://www.mouser.com/datasheet/3/76/2/GCM1555C1H5R6BA16_01A.pdf"
			(at 0 0 90)
			(layer "F.Fab")
			(hide yes)
			(effects
				(font
					(size 1.27 1.27)
					(thickness 0.15)
				)
			)
		)
		(property "Description" "Multilayer Ceramic Capacitors MLCC - SMD/SMT 5.6 pF 50 VDC 0.1 pF 0402 C0G (NP0) AEC-Q200"
			(at 0 0 90)
			(layer "F.Fab")
			(hide yes)
			(effects
				(font
					(size 1.27 1.27)
					(thickness 0.15)
				)
			)
		)
		(property "MPN" "GCM1555C1H5R6BA16D"
			(at 0 0 270)
			(unlocked yes)
			(layer "F.Fab")
			(hide yes)
			(effects
				(font
					(size 1 1)
					(thickness 0.15)
				)
			)
		)
		(property "Manufacturer" "Murata"
			(at 0 0 270)
			(unlocked yes)
			(layer "F.Fab")
			(hide yes)
			(effects
				(font
					(size 1 1)
					(thickness 0.15)
				)
			)
		)
		(property "License" "Apache-2.0"
			(at 0 0 270)
			(unlocked yes)
			(layer "F.Fab")
			(hide yes)
			(effects
				(font
					(size 1 1)
					(thickness 0.15)
				)
			)
		)
		(property "Author" "Antmicro"
			(at 0 0 270)
			(unlocked yes)
			(layer "F.Fab")
			(hide yes)
			(effects
				(font
					(size 1 1)
					(thickness 0.15)
				)
			)
		)
		(property "Val" "5p6"
			(at 0 0 270)
			(unlocked yes)
			(layer "F.Fab")
			(hide yes)
			(effects
				(font
					(size 1 1)
					(thickness 0.15)
				)
			)
		)
		(property "Voltage" "50V"
			(at 0 0 270)
			(unlocked yes)
			(layer "F.Fab")
			(hide yes)
			(effects
				(font
					(size 1 1)
					(thickness 0.15)
				)
			)
		)
		(property "Dielectric" "C0G"
			(at 0 0 270)
			(unlocked yes)
			(layer "F.Fab")
			(hide yes)
			(effects
				(font
					(size 1 1)
					(thickness 0.15)
				)
			)
		)
		(sheetname "/X710-AT2 Misc/")
		(sheetfile "x710-at2-mics.kicad_sch")
		(attr smd)
		(fp_rect
			(start -0.925 -0.47)
			(end 0.925 0.47)
			(stroke
				(width 0.05)
				(type default)
			)
			(fill no)
			(layer "F.CrtYd")
		)
		(fp_line
			(start -0.494 0.248)
			(end -0.494 -0.25)
			(stroke
				(width 0.15)
				(type solid)
			)
			(layer "F.Fab")
		)
		(fp_line
			(start 0.504 0.248)
			(end -0.494 0.248)
			(stroke
				(width 0.15)
				(type solid)
			)
			(layer "F.Fab")
		)
		(fp_line
			(start -0.494 -0.25)
			(end 0.504 -0.25)
			(stroke
				(width 0.15)
				(type solid)
			)
			(layer "F.Fab")
		)
		(fp_line
			(start 0.504 -0.25)
			(end 0.504 0.248)
			(stroke
				(width 0.15)
				(type solid)
			)
			(layer "F.Fab")
		)
		(pad "1" smd roundrect
			(at -0.48 0 270)
			(size 0.59 0.64)
			(layers "F.Cu" "F.Mask" "F.Paste")
			(roundrect_rratio 0.25)
			(net 28 "GND")
			(pintype "passive")
		)
		(pad "2" smd roundrect
			(at 0.48 0 270)
			(size 0.59 0.64)
			(layers "F.Cu" "F.Mask" "F.Paste")
			(roundrect_rratio 0.25)
			(net 77 "/X710-AT2 Misc/50MHZ_XTAL_R.-")
			(pintype "passive")
		)
	)
	(footprint "antmicro-footprints:C_0402_1005Metric"
		(layer "F.Cu")
		(at 97.498001 62.778655 -90)
		(descr "Capacitor SMD 0402")
		(tags "capacitor SMD 0402")
		(property "Reference" "C195"
			(at 1.806345 -2.351999 270)
			(layer "F.SilkS")
			(effects
				(font
					(size 0.7 0.7)
					(thickness 0.15)
				)
				(justify left bottom)
			)
		)
		(property "Value" "C_220n_16V_0402"
			(at -1.022927 2.155213 270)
			(layer "F.Fab")
			(hide yes)
			(effects
				(font
					(size 0.7 0.7)
					(thickness 0.15)
				)
				(justify left bottom)
			)
		)
		(property "Datasheet" "https://www.murata.com/products/productdetail?partno=GRM155R71C224KA12%23"
			(at 0 0 270)
			(layer "F.Fab")
			(hide yes)
			(effects
				(font
					(size 1.27 1.27)
					(thickness 0.15)
				)
			)
		)
		(property "Description" "SMD Multilayer Ceramic Capacitor, 0.22 µF, 16 V, 0402 [1005 Metric], ± 10%, X7R, GRM Series"
			(at 0 0 270)
			(layer "F.Fab")
			(hide yes)
			(effects
				(font
					(size 1.27 1.27)
					(thickness 0.15)
				)
			)
		)
		(property "MPN" "GRM155R71C224KA12D"
			(at 0 0 270)
			(unlocked yes)
			(layer "F.Fab")
			(hide yes)
			(effects
				(font
					(size 1 1)
					(thickness 0.15)
				)
			)
		)
		(property "Manufacturer" "Murata"
			(at 0 0 270)
			(unlocked yes)
			(layer "F.Fab")
			(hide yes)
			(effects
				(font
					(size 1 1)
					(thickness 0.15)
				)
			)
		)
		(property "License" "Apache-2.0"
			(at 0 0 270)
			(unlocked yes)
			(layer "F.Fab")
			(hide yes)
			(effects
				(font
					(size 1 1)
					(thickness 0.15)
				)
			)
		)
		(property "Author" "Antmicro"
			(at 0 0 270)
			(unlocked yes)
			(layer "F.Fab")
			(hide yes)
			(effects
				(font
					(size 1 1)
					(thickness 0.15)
				)
			)
		)
		(property "Val" "220n"
			(at 0 0 270)
			(unlocked yes)
			(layer "F.Fab")
			(hide yes)
			(effects
				(font
					(size 1 1)
					(thickness 0.15)
				)
			)
		)
		(property "Voltage" "16V"
			(at 0 0 270)
			(unlocked yes)
			(layer "F.Fab")
			(hide yes)
			(effects
				(font
					(size 1 1)
					(thickness 0.15)
				)
			)
		)
		(property "Dielectric" "X7R"
			(at 0 0 270)
			(unlocked yes)
			(layer "F.Fab")
			(hide yes)
			(effects
				(font
					(size 1 1)
					(thickness 0.15)
				)
			)
		)
		(sheetname "/X710-AT2 PCIe/")
		(sheetfile "x710-at2-pcie.kicad_sch")
		(attr smd)
		(fp_rect
			(start -0.925 -0.47)
			(end 0.925 0.47)
			(stroke
				(width 0.05)
				(type default)
			)
			(fill no)
			(layer "F.CrtYd")
		)
		(fp_line
			(start -0.494 0.248)
			(end -0.494 -0.25)
			(stroke
				(width 0.15)
				(type solid)
			)
			(layer "F.Fab")
		)
		(fp_line
			(start 0.504 0.248)
			(end -0.494 0.248)
			(stroke
				(width 0.15)
				(type solid)
			)
			(layer "F.Fab")
		)
		(fp_line
			(start -0.494 -0.25)
			(end 0.504 -0.25)
			(stroke
				(width 0.15)
				(type solid)
			)
			(layer "F.Fab")
		)
		(fp_line
			(start 0.504 -0.25)
			(end 0.504 0.248)
			(stroke
				(width 0.15)
				(type solid)
			)
			(layer "F.Fab")
		)
		(pad "1" smd roundrect
			(at -0.48 0 270)
			(size 0.59 0.64)
			(layers "F.Cu" "F.Mask" "F.Paste")
			(roundrect_rratio 0.25)
			(net 22 "/OCuLink/PCIe_{x4}.TX2-")
			(pintype "passive")
		)
		(pad "2" smd roundrect
			(at 0.48 0 270)
			(size 0.59 0.64)
			(layers "F.Cu" "F.Mask" "F.Paste")
			(roundrect_rratio 0.25)
			(net 41 "/X710-AT2 PCIe/PCIe_{x4}_AC.TX2-")
			(pintype "passive")
		)
	)
)
